(kicad_pcb
	(version 20260206)
	(generator "pcbnew")
	(generator_version "10.0")
	(general
		(thickness 1.6)
		(legacy_teardrops no)
	)
	(paper "A4")
	(title_block
		(title "Bryce Canyon_SCC_16316-1_OCP.brd")
		(comment 1 "Bryce Canyon / footprints 864-872 of 1561")
	)
	(layers
		(0 "F.Cu" signal "TOP")
		(4 "In1.Cu" signal "L2GND")
		(6 "In2.Cu" signal "L3")
		(8 "In3.Cu" signal "L4VCC")
		(10 "In4.Cu" signal "L5VCC")
		(12 "In5.Cu" signal "L6")
		(14 "In6.Cu" signal "L7GND")
		(2 "B.Cu" signal "BOTTOM")
		(9 "F.Adhes" user "F.Adhesive")
		(11 "B.Adhes" user "B.Adhesive")
		(13 "F.Paste" user "Package Geometry/Pastemask Top")
		(15 "B.Paste" user "Package Geometry/Pastemask Bottom")
		(5 "F.SilkS" user "Ref Des/Silkscreen Top")
		(7 "B.SilkS" user "Ref Des/Silkscreen Bottom")
		(1 "F.Mask" user "Board Geometry/Soldermask Top")
		(3 "B.Mask" user "Board Geometry/Soldermask Bottom")
		(17 "Dwgs.User" user "User.Drawings")
		(19 "Cmts.User" user "User.Comments")
		(21 "Eco1.User" user "User.Eco1")
		(23 "Eco2.User" user "User.Eco2")
		(25 "Edge.Cuts" user "Board Geometry/Outline")
		(27 "Margin" user)
		(31 "F.CrtYd" user "Package Geometry/Place Bound Top")
		(29 "B.CrtYd" user "Package Geometry/Place Bound Bottom")
		(35 "F.Fab" user "Ref Des/Assembly Top")
		(33 "B.Fab" user "Ref Des/Assembly Bottom")
	)
	(footprint ""
		(layer "B.Cu")
		(at 107.500166 -81.500218)
		(property "Reference" "TP41"
			(at 0 0 0)
			(layer "B.SilkS")
			(hide yes)
			(effects
				(font
					(size 1.27 1.27)
				)
				(justify mirror)
			)
		)
		(property "Value" "TPAD28-2-GP"
			(at 0.0127 -1.6637 0)
			(unlocked yes)
			(layer "B.Fab")
			(hide yes)
			(effects
				(font
					(size 1.016 1.016)
					(thickness 0.1524)
				)
				(justify mirror)
			)
		)
		(property "Device Type" "TPAD28"
			(at 0.0127 -3.1877 0)
			(unlocked yes)
			(layer "B.Fab")
			(hide yes)
			(effects
				(font
					(size 1.016 1.016)
					(thickness 0.1524)
				)
				(justify mirror)
			)
		)
		(duplicate_pad_numbers_are_jumpers no)
		(fp_poly
			(pts
				(arc
					(start 0.3556 0)
					(mid -0.3556 0)
					(end 0.3556 0)
				)
			)
			(stroke
				(width 0)
				(type default)
			)
			(fill no)
			(layer "B.CrtYd")
		)
		(fp_poly
			(pts
				(arc
					(start 0.6096 0)
					(mid -0.6096 0)
					(end 0.6096 0)
				)
			)
			(stroke
				(width 0)
				(type default)
			)
			(fill no)
			(layer "B.Fab")
		)
		(pad "1" smd circle
			(at 0 0 180)
			(size 0.7112 0.7112)
			(layers "B.Cu" "B.Mask" "B.Paste")
			(net "LSI_TRST_N")
		)
	)
	(footprint ""
		(layer "B.Cu")
		(at 156.978604 -66.866008)
		(property "Reference" "R279"
			(at 0 0 0)
			(layer "B.SilkS")
			(hide yes)
			(effects
				(font
					(size 1.27 1.27)
				)
				(justify mirror)
			)
		)
		(property "Value" "10R2F-L-GP"
			(at -0.064008 -3.993896 0)
			(unlocked yes)
			(layer "B.Fab")
			(hide yes)
			(effects
				(font
					(size 1.016 1.016)
					(thickness 0.1524)
				)
				(justify mirror)
			)
		)
		(property "Device Type" "R402H14"
			(at -0.064008 -5.517896 0)
			(unlocked yes)
			(layer "B.Fab")
			(hide yes)
			(effects
				(font
					(size 1.016 1.016)
					(thickness 0.1524)
				)
				(justify mirror)
			)
		)
		(duplicate_pad_numbers_are_jumpers no)
		(fp_line
			(start -0.508 -0.9398)
			(end 0.508 -0.9398)
			(stroke
				(width 0.1524)
				(type default)
			)
			(layer "B.SilkS")
		)
		(fp_line
			(start 0.508 -0.9398)
			(end 0.508 0.9398)
			(stroke
				(width 0.1524)
				(type default)
			)
			(layer "B.SilkS")
		)
		(fp_rect
			(start 0.508 0.9398)
			(end -0.508 -0.9398)
			(stroke
				(width 0)
				(type default)
			)
			(fill no)
			(layer "B.CrtYd")
		)
		(fp_rect
			(start 0.508 0.9398)
			(end -0.508 -0.9398)
			(stroke
				(width 0)
				(type default)
			)
			(fill no)
			(layer "B.Fab")
		)
		(pad "1" smd custom
			(at 0 -0.4445 180)
			(size 0.1397 0.1397)
			(layers "B.Cu" "B.Mask" "B.Paste")
			(net "P1V8_C")
			(options
				(clearance outline)
				(anchor circle)
			)
			(primitives
				(gr_poly
					(pts
						(arc
							(start -0.1778 0.2794)
							(mid -0.249642 0.249642)
							(end -0.2794 0.1778)
						)
						(arc
							(start -0.2794 -0.1778)
							(mid -0.249642 -0.249642)
							(end -0.1778 -0.2794)
						)
						(arc
							(start 0.1778 -0.2794)
							(mid 0.249642 -0.249642)
							(end 0.2794 -0.1778)
						)
						(arc
							(start 0.2794 0.1778)
							(mid 0.249642 0.249642)
							(end 0.1778 0.2794)
						)
					)
					(width 0)
					(fill yes)
				)
			)
		)
		(pad "2" smd custom
			(at 0 0.4445 180)
			(size 0.1397 0.1397)
			(layers "B.Cu" "B.Mask" "B.Paste")
			(net "SHELL_PLL_VDD")
			(options
				(clearance outline)
				(anchor circle)
			)
			(primitives
				(gr_poly
					(pts
						(arc
							(start -0.1778 0.2794)
							(mid -0.249642 0.249642)
							(end -0.2794 0.1778)
						)
						(arc
							(start -0.2794 -0.1778)
							(mid -0.249642 -0.249642)
							(end -0.1778 -0.2794)
						)
						(arc
							(start 0.1778 -0.2794)
							(mid 0.249642 -0.249642)
							(end 0.2794 -0.1778)
						)
						(arc
							(start 0.2794 0.1778)
							(mid 0.249642 0.249642)
							(end 0.1778 0.2794)
						)
					)
					(width 0)
					(fill yes)
				)
			)
		)
	)
	(footprint ""
		(layer "B.Cu")
		(at 187.452 -34.0106 90)
		(property "Reference" "TP95"
			(at 0 0 90)
			(layer "B.SilkS")
			(hide yes)
			(effects
				(font
					(size 1.27 1.27)
				)
				(justify mirror)
			)
		)
		(property "Value" "TPAD28-2-GP"
			(at 0.0127 -1.6637 90)
			(unlocked yes)
			(layer "B.Fab")
			(hide yes)
			(effects
				(font
					(size 1.016 1.016)
					(thickness 0.1524)
				)
				(justify mirror)
			)
		)
		(property "Device Type" "TPAD28"
			(at 0.0127 -3.1877 90)
			(unlocked yes)
			(layer "B.Fab")
			(hide yes)
			(effects
				(font
					(size 1.016 1.016)
					(thickness 0.1524)
				)
				(justify mirror)
			)
		)
		(duplicate_pad_numbers_are_jumpers no)
		(fp_poly
			(pts
				(arc
					(start 0 0.3556)
					(mid 0 -0.3556)
					(end 0 0.3556)
				)
			)
			(stroke
				(width 0)
				(type default)
			)
			(fill no)
			(layer "B.CrtYd")
		)
		(fp_poly
			(pts
				(arc
					(start 0 0.6096)
					(mid 0 -0.6096)
					(end 0 0.6096)
				)
			)
			(stroke
				(width 0)
				(type default)
			)
			(fill no)
			(layer "B.Fab")
		)
		(pad "1" smd circle
			(at 0 0 270)
			(size 0.7112 0.7112)
			(layers "B.Cu" "B.Mask" "B.Paste")
			(net "IOC_GPIO_34")
		)
	)
	(footprint ""
		(layer "B.Cu")
		(at 184.3024 -26.3144 90)
		(property "Reference" "TP54"
			(at 0 0 90)
			(layer "B.SilkS")
			(hide yes)
			(effects
				(font
					(size 1.27 1.27)
				)
				(justify mirror)
			)
		)
		(property "Value" "TPAD28-2-GP"
			(at 0.0127 -1.6637 90)
			(unlocked yes)
			(layer "B.Fab")
			(hide yes)
			(effects
				(font
					(size 1.016 1.016)
					(thickness 0.1524)
				)
				(justify mirror)
			)
		)
		(property "Device Type" "TPAD28"
			(at 0.0127 -3.1877 90)
			(unlocked yes)
			(layer "B.Fab")
			(hide yes)
			(effects
				(font
					(size 1.016 1.016)
					(thickness 0.1524)
				)
				(justify mirror)
			)
		)
		(duplicate_pad_numbers_are_jumpers no)
		(fp_poly
			(pts
				(arc
					(start 0 0.3556)
					(mid 0 -0.3556)
					(end 0 0.3556)
				)
			)
			(stroke
				(width 0)
				(type default)
			)
			(fill no)
			(layer "B.CrtYd")
		)
		(fp_poly
			(pts
				(arc
					(start 0 0.6096)
					(mid 0 -0.6096)
					(end 0 0.6096)
				)
			)
			(stroke
				(width 0)
				(type default)
			)
			(fill no)
			(layer "B.Fab")
		)
		(pad "1" smd circle
			(at 0 0 270)
			(size 0.7112 0.7112)
			(layers "B.Cu" "B.Mask" "B.Paste")
			(net "IOC_GPIO_1")
		)
	)
	(footprint ""
		(layer "B.Cu")
		(at 66.7004 -105.1306 180)
		(property "Reference" "R515"
			(at 0 0 0)
			(layer "B.SilkS")
			(hide yes)
			(effects
				(font
					(size 1.27 1.27)
				)
				(justify mirror)
			)
		)
		(property "Value" "2D2R3-1-U-GP"
			(at 0.0254 -2.5146 180)
			(unlocked yes)
			(layer "B.Fab")
			(hide yes)
			(effects
				(font
					(size 1.016 1.016)
					(thickness 0.1524)
				)
				(justify mirror)
			)
		)
		(property "Device Type" "R603H22"
			(at 0.0254 -4.0386 180)
			(unlocked yes)
			(layer "B.Fab")
			(hide yes)
			(effects
				(font
					(size 1.016 1.016)
					(thickness 0.1524)
				)
				(justify mirror)
			)
		)
		(duplicate_pad_numbers_are_jumpers no)
		(fp_line
			(start 0.4826 0)
			(end 0.2032 0)
			(stroke
				(width 0.2032)
				(type default)
			)
			(layer "B.SilkS")
		)
		(fp_line
			(start -0.2032 0)
			(end -0.4826 0)
			(stroke
				(width 0.2032)
				(type default)
			)
			(layer "B.SilkS")
		)
		(fp_rect
			(start 0.5842 1.3335)
			(end -0.5842 -1.3335)
			(stroke
				(width 0)
				(type default)
			)
			(fill no)
			(layer "B.CrtYd")
		)
		(fp_rect
			(start 0.5842 1.3335)
			(end -0.5842 -1.3335)
			(stroke
				(width 0)
				(type default)
			)
			(fill no)
			(layer "B.Fab")
		)
		(pad "1" smd custom
			(at 0 -0.762)
			(size 0.2159 0.2159)
			(layers "B.Cu" "B.Mask" "B.Paste")
			(net "P3V3_VBST")
			(options
				(clearance outline)
				(anchor circle)
			)
			(primitives
				(gr_poly
					(pts
						(arc
							(start -0.3302 0.4318)
							(mid -0.402042 0.402042)
							(end -0.4318 0.3302)
						)
						(arc
							(start -0.4318 -0.3302)
							(mid -0.402042 -0.402042)
							(end -0.3302 -0.4318)
						)
						(arc
							(start 0.3302 -0.4318)
							(mid 0.402042 -0.402042)
							(end 0.4318 -0.3302)
						)
						(arc
							(start 0.4318 0.3302)
							(mid 0.402042 0.402042)
							(end 0.3302 0.4318)
						)
					)
					(width 0)
					(fill yes)
				)
			)
		)
		(pad "2" smd custom
			(at 0 0.762)
			(size 0.2159 0.2159)
			(layers "B.Cu" "B.Mask" "B.Paste")
			(net "P3V3_VBST_RC")
			(options
				(clearance outline)
				(anchor circle)
			)
			(primitives
				(gr_poly
					(pts
						(arc
							(start -0.3302 0.4318)
							(mid -0.402042 0.402042)
							(end -0.4318 0.3302)
						)
						(arc
							(start -0.4318 -0.3302)
							(mid -0.402042 -0.402042)
							(end -0.3302 -0.4318)
						)
						(arc
							(start 0.3302 -0.4318)
							(mid 0.402042 -0.402042)
							(end 0.4318 -0.3302)
						)
						(arc
							(start 0.4318 0.3302)
							(mid 0.402042 0.402042)
							(end 0.3302 0.4318)
						)
					)
					(width 0)
					(fill yes)
				)
			)
		)
	)
	(footprint ""
		(layer "B.Cu")
		(at 136.2202 -79.0448 -90)
		(property "Reference" "C3"
			(at 0 0 90)
			(layer "B.SilkS")
			(hide yes)
			(effects
				(font
					(size 1.27 1.27)
				)
				(justify mirror)
			)
		)
		(property "Value" "SCD01U16V1KX-GP"
			(at 2.8321 -1.7399 270)
			(unlocked yes)
			(layer "B.Fab")
			(hide yes)
			(effects
				(font
					(size 1.016 1.016)
					(thickness 0.1524)
				)
				(justify mirror)
			)
		)
		(property "Device Type" "C0201H13"
			(at 2.8321 -3.2639 270)
			(unlocked yes)
			(layer "B.Fab")
			(hide yes)
			(effects
				(font
					(size 1.016 1.016)
					(thickness 0.1524)
				)
				(justify mirror)
			)
		)
		(duplicate_pad_numbers_are_jumpers no)
		(fp_rect
			(start 0.2794 0.6477)
			(end -0.2794 -0.6477)
			(stroke
				(width 0)
				(type default)
			)
			(fill no)
			(layer "B.CrtYd")
		)
		(fp_rect
			(start 0.2794 0.6477)
			(end -0.2794 -0.6477)
			(stroke
				(width 0)
				(type default)
			)
			(fill no)
			(layer "B.Fab")
		)
		(pad "1" smd custom
			(at 0 -0.2794 90)
			(size 0.0762 0.0762)
			(layers "B.Cu" "B.Mask" "B.Paste")
			(net "PHY_CONN_TO_EXP_10_DP")
			(options
				(clearance outline)
				(anchor circle)
			)
			(primitives
				(gr_poly
					(pts
						(arc
							(start 0.1524 0.127)
							(mid 0.137521 0.162921)
							(end 0.1016 0.1778)
						)
						(arc
							(start -0.1016 0.1778)
							(mid -0.137521 0.162921)
							(end -0.1524 0.127)
						)
						(arc
							(start -0.1524 -0.127)
							(mid -0.137521 -0.162921)
							(end -0.1016 -0.1778)
						)
						(arc
							(start 0.1016 -0.1778)
							(mid 0.137521 -0.162921)
							(end 0.1524 -0.127)
						)
					)
					(width 0)
					(fill yes)
				)
			)
		)
		(pad "2" smd custom
			(at 0 0.2794 90)
			(size 0.0762 0.0762)
			(layers "B.Cu" "B.Mask" "B.Paste")
			(net "PHY_CONN_TO_EXP_C_10_DP")
			(options
				(clearance outline)
				(anchor circle)
			)
			(primitives
				(gr_poly
					(pts
						(arc
							(start 0.1524 0.127)
							(mid 0.137521 0.162921)
							(end 0.1016 0.1778)
						)
						(arc
							(start -0.1016 0.1778)
							(mid -0.137521 0.162921)
							(end -0.1524 0.127)
						)
						(arc
							(start -0.1524 -0.127)
							(mid -0.137521 -0.162921)
							(end -0.1016 -0.1778)
						)
						(arc
							(start 0.1016 -0.1778)
							(mid 0.137521 -0.162921)
							(end 0.1524 -0.127)
						)
					)
					(width 0)
					(fill yes)
				)
			)
		)
	)
	(footprint ""
		(layer "B.Cu")
		(at 105.283 -67.056)
		(property "Reference" "C211"
			(at 0 0 0)
			(layer "B.SilkS")
			(hide yes)
			(effects
				(font
					(size 1.27 1.27)
				)
				(justify mirror)
			)
		)
		(property "Value" "SCD1U6D3V1KX-GP"
			(at 2.8321 -1.7399 0)
			(unlocked yes)
			(layer "B.Fab")
			(hide yes)
			(effects
				(font
					(size 1.016 1.016)
					(thickness 0.1524)
				)
				(justify mirror)
			)
		)
		(property "Device Type" "C0201H13"
			(at 2.8321 -3.2639 0)
			(unlocked yes)
			(layer "B.Fab")
			(hide yes)
			(effects
				(font
					(size 1.016 1.016)
					(thickness 0.1524)
				)
				(justify mirror)
			)
		)
		(duplicate_pad_numbers_are_jumpers no)
		(fp_rect
			(start 0.2794 0.6477)
			(end -0.2794 -0.6477)
			(stroke
				(width 0)
				(type default)
			)
			(fill no)
			(layer "B.CrtYd")
		)
		(fp_rect
			(start 0.2794 0.6477)
			(end -0.2794 -0.6477)
			(stroke
				(width 0)
				(type default)
			)
			(fill no)
			(layer "B.Fab")
		)
		(pad "1" smd custom
			(at 0 -0.2794 180)
			(size 0.0762 0.0762)
			(layers "B.Cu" "B.Mask" "B.Paste")
			(net "SYSPLL_VDDA09")
			(options
				(clearance outline)
				(anchor circle)
			)
			(primitives
				(gr_poly
					(pts
						(arc
							(start 0.1524 0.127)
							(mid 0.137521 0.162921)
							(end 0.1016 0.1778)
						)
						(arc
							(start -0.1016 0.1778)
							(mid -0.137521 0.162921)
							(end -0.1524 0.127)
						)
						(arc
							(start -0.1524 -0.127)
							(mid -0.137521 -0.162921)
							(end -0.1016 -0.1778)
						)
						(arc
							(start 0.1016 -0.1778)
							(mid 0.137521 -0.162921)
							(end 0.1524 -0.127)
						)
					)
					(width 0)
					(fill yes)
				)
			)
		)
		(pad "2" smd custom
			(at 0 0.2794 180)
			(size 0.0762 0.0762)
			(layers "B.Cu" "B.Mask" "B.Paste")
			(net "GND")
			(options
				(clearance outline)
				(anchor circle)
			)
			(primitives
				(gr_poly
					(pts
						(arc
							(start 0.1524 0.127)
							(mid 0.137521 0.162921)
							(end 0.1016 0.1778)
						)
						(arc
							(start -0.1016 0.1778)
							(mid -0.137521 0.162921)
							(end -0.1524 0.127)
						)
						(arc
							(start -0.1524 -0.127)
							(mid -0.137521 -0.162921)
							(end -0.1016 -0.1778)
						)
						(arc
							(start 0.1016 -0.1778)
							(mid 0.137521 -0.162921)
							(end 0.1524 -0.127)
						)
					)
					(width 0)
					(fill yes)
				)
			)
		)
	)
	(footprint ""
		(layer "B.Cu")
		(at 118.754398 -68.629784)
		(property "Reference" "C183"
			(at 0 0 0)
			(layer "B.SilkS")
			(hide yes)
			(effects
				(font
					(size 1.27 1.27)
				)
				(justify mirror)
			)
		)
		(property "Value" "SC10U6D3V2MX-GP-U"
			(at 1.524 -1.905 0)
			(unlocked yes)
			(layer "B.Fab")
			(hide yes)
			(effects
				(font
					(size 1.016 1.016)
					(thickness 0.1524)
				)
				(justify mirror)
			)
		)
		(property "Device Type" "C402-TO0D2H28"
			(at 1.524 -3.429 0)
			(unlocked yes)
			(layer "B.Fab")
			(hide yes)
			(effects
				(font
					(size 1.016 1.016)
					(thickness 0.1524)
				)
				(justify mirror)
			)
		)
		(duplicate_pad_numbers_are_jumpers no)
		(fp_rect
			(start 0.4826 0.889)
			(end -0.4826 -0.889)
			(stroke
				(width 0)
				(type default)
			)
			(fill no)
			(layer "B.CrtYd")
		)
		(fp_rect
			(start 0.4826 0.889)
			(end -0.4826 -0.889)
			(stroke
				(width 0)
				(type default)
			)
			(fill no)
			(layer "B.Fab")
		)
		(pad "1" smd custom
			(at 0 -0.4572 180)
			(size 0.1524 0.1524)
			(layers "B.Cu" "B.Mask" "B.Paste")
			(net "P0V9")
			(options
				(clearance outline)
				(anchor circle)
			)
			(primitives
				(gr_poly
					(pts
						(arc
							(start -0.254 -0.3048)
							(mid -0.325842 -0.275042)
							(end -0.3556 -0.2032)
						)
						(arc
							(start -0.3556 0.2032)
							(mid -0.325842 0.275042)
							(end -0.254 0.3048)
						)
						(arc
							(start 0.254 0.3048)
							(mid 0.325842 0.275042)
							(end 0.3556 0.2032)
						)
						(arc
							(start 0.3556 -0.2032)
							(mid 0.325842 -0.275042)
							(end 0.254 -0.3048)
						)
					)
					(width 0)
					(fill yes)
				)
			)
		)
		(pad "2" smd custom
			(at 0 0.4572 180)
			(size 0.1524 0.1524)
			(layers "B.Cu" "B.Mask" "B.Paste")
			(net "GND")
			(options
				(clearance outline)
				(anchor circle)
			)
			(primitives
				(gr_poly
					(pts
						(arc
							(start -0.254 -0.3048)
							(mid -0.325842 -0.275042)
							(end -0.3556 -0.2032)
						)
						(arc
							(start -0.3556 0.2032)
							(mid -0.325842 0.275042)
							(end -0.254 0.3048)
						)
						(arc
							(start 0.254 0.3048)
							(mid 0.325842 0.275042)
							(end 0.3556 0.2032)
						)
						(arc
							(start 0.3556 -0.2032)
							(mid 0.325842 -0.275042)
							(end 0.254 -0.3048)
						)
					)
					(width 0)
					(fill yes)
				)
			)
		)
	)
	(footprint ""
		(layer "B.Cu")
		(at 170.602148 -41.194482 -90)
		(property "Reference" "C409"
			(at 0 0 90)
			(layer "B.SilkS")
			(hide yes)
			(effects
				(font
					(size 1.27 1.27)
				)
				(justify mirror)
			)
		)
		(property "Value" "SC10U6D3V5KX-4GP"
			(at 0.0762 -6.1214 270)
			(unlocked yes)
			(layer "B.Fab")
			(hide yes)
			(effects
				(font
					(size 1.016 1.016)
					(thickness 0.1524)
				)
				(justify mirror)
			)
		)
		(property "Device Type" "C805H58"
			(at 0.0762 -8.1534 270)
			(unlocked yes)
			(layer "B.Fab")
			(hide yes)
			(effects
				(font
					(size 1.016 1.016)
					(thickness 0.1524)
				)
				(justify mirror)
			)
		)
		(duplicate_pad_numbers_are_jumpers no)
		(fp_line
			(start -0.635 0)
			(end 0.635 0)
			(stroke
				(width 0.508)
				(type default)
			)
			(layer "B.SilkS")
		)
		(fp_rect
			(start 0.9652 1.778)
			(end -0.9652 -1.778)
			(stroke
				(width 0)
				(type default)
			)
			(fill no)
			(layer "B.CrtYd")
		)
		(fp_poly
			(pts
				(xy 0.9652 -1.778) (xy -0.9652 -1.778) (xy -0.9652 1.778) (xy 0.9652 1.778)
			)
			(stroke
				(width 0)
				(type default)
			)
			(fill no)
			(layer "B.Fab")
		)
		(pad "1" smd rect
			(at 0 -0.9652 90)
			(size 1.397 1.143)
			(layers "B.Cu" "B.Mask" "B.Paste")
			(net "P0V975")
		)
		(pad "2" smd rect
			(at 0 0.9652 90)
			(size 1.397 1.143)
			(layers "B.Cu" "B.Mask" "B.Paste")
			(net "GND")
		)
	)
)
